# S9S_MB_2U (Grand Teton) — schematic netlist excerpt (pin names and nets, part order shuffled) for the footprints in the layout excerpt that follows; sources: Cadence DE-HDL packaged netlist, KiCad conversion of 03242023_DA0F0TMBIJ0_F0T_Motherboard_J_brd_V01_OCP.brd

R3888  Q_RES  49.9 1% CHIP  pkg 0402LF  page 95 : A = I3C_SPD_DDREFGH_CPU0_LVC1_SCL_5 ; B = I3C_SPD_DDREFGH_CPU0_LVC1_SCL
R262  Q_RES  240 1% EMPTY  pkg 0402LF  page 119 : A = PVNN_TERM_CPU1 ; B = PU_CPU1_SAFE_MODE_BOOT

(kicad_pcb
	(version 20260206)
	(generator "pcbnew")
	(generator_version "10.0")
	(general
		(thickness 1.6)
		(legacy_teardrops no)
	)
	(paper "A4")
	(title_block
		(title "03242023_DA0F0TMBIJ0_F0T_Motherboard_J_brd_V01_OCP.brd")
		(comment 1 "Grand Teton / footprints 5353-5354 of 6105")
	)
	(layers
		(0 "F.Cu" signal "TOP")
		(4 "In1.Cu" signal "GND")
		(6 "In2.Cu" signal "IN1")
		(8 "In3.Cu" signal "GND1")
		(10 "In4.Cu" signal "IN2")
		(12 "In5.Cu" signal "GND2")
		(14 "In6.Cu" signal "IN3")
		(16 "In7.Cu" signal "GND3")
		(18 "In8.Cu" signal "VCC")
		(20 "In9.Cu" signal "VCC1")
		(22 "In10.Cu" signal "GND4")
		(24 "In11.Cu" signal "IN4")
		(26 "In12.Cu" signal "GND5")
		(28 "In13.Cu" signal "IN5")
		(30 "In14.Cu" signal "GND6")
		(32 "In15.Cu" signal "IN6")
		(34 "In16.Cu" signal "GND7")
		(2 "B.Cu" signal "BOTTOM")
		(9 "F.Adhes" user "F.Adhesive")
		(11 "B.Adhes" user "B.Adhesive")
		(13 "F.Paste" user "Package Geometry/Pastemask Top")
		(15 "B.Paste" user "Package Geometry/Pastemask Bottom")
		(5 "F.SilkS" user "Ref Des/Silkscreen Top")
		(7 "B.SilkS" user "Ref Des/Silkscreen Bottom")
		(1 "F.Mask" user "Board Geometry/Soldermask Top")
		(3 "B.Mask" user "Board Geometry/Soldermask Bottom")
		(17 "Dwgs.User" user "User.Drawings")
		(19 "Cmts.User" user "User.Comments")
		(21 "Eco1.User" user "User.Eco1")
		(23 "Eco2.User" user "User.Eco2")
		(25 "Edge.Cuts" user "Board Geometry/Outline")
		(27 "Margin" user)
		(31 "F.CrtYd" user "Package Geometry/Place Bound Top")
		(29 "B.CrtYd" user "Package Geometry/Place Bound Bottom")
		(35 "F.Fab" user "Ref Des/Assembly Top")
		(33 "B.Fab" user "Ref Des/Assembly Bottom")
	)
	(footprint ""
		(layer "B.Cu")
		(at 436.926482 -317.848996 90)
		(property "Reference" "R3888"
			(at 0 0 90)
			(layer "B.SilkS")
			(hide yes)
			(effects
				(font
					(size 1.27 1.27)
				)
				(justify mirror)
			)
		)
		(property "Value" ""
			(at 0 0 90)
			(layer "B.Fab")
			(effects
				(font
					(size 1.27 1.27)
				)
				(justify mirror)
			)
		)
		(duplicate_pad_numbers_are_jumpers no)
		(fp_line
			(start 0.7874 -0.4064)
			(end -0.7874 -0.4064)
			(stroke
				(width 0.1524)
				(type default)
			)
			(layer "B.SilkS")
		)
		(fp_line
			(start -0.7874 -0.4064)
			(end -0.7874 0.4064)
			(stroke
				(width 0.1524)
				(type default)
			)
			(layer "B.SilkS")
		)
		(fp_line
			(start 0.7874 0.4064)
			(end 0.7874 -0.4064)
			(stroke
				(width 0.1524)
				(type default)
			)
			(layer "B.SilkS")
		)
		(fp_line
			(start -0.7874 0.4064)
			(end 0.7874 0.4064)
			(stroke
				(width 0.1524)
				(type default)
			)
			(layer "B.SilkS")
		)
		(fp_line
			(start 0.67945 -0.305054)
			(end 0.12065 -0.305054)
			(stroke
				(width 0.1)
				(type default)
			)
			(layer "B.Fab")
		)
		(fp_line
			(start 0.12065 -0.305054)
			(end 0.12065 -0.2794)
			(stroke
				(width 0.1)
				(type default)
			)
			(layer "B.Fab")
		)
		(fp_line
			(start -0.12065 -0.3048)
			(end -0.67945 -0.3048)
			(stroke
				(width 0.1)
				(type default)
			)
			(layer "B.Fab")
		)
		(fp_line
			(start -0.67945 -0.3048)
			(end -0.67945 0.3048)
			(stroke
				(width 0.1)
				(type default)
			)
			(layer "B.Fab")
		)
		(fp_line
			(start 0.12065 -0.2794)
			(end -0.12065 -0.2794)
			(stroke
				(width 0.1)
				(type default)
			)
			(layer "B.Fab")
		)
		(fp_line
			(start -0.12065 -0.2794)
			(end -0.12065 -0.3048)
			(stroke
				(width 0.1)
				(type default)
			)
			(layer "B.Fab")
		)
		(fp_line
			(start 0.12065 0.2794)
			(end 0.12065 0.3048)
			(stroke
				(width 0.1)
				(type default)
			)
			(layer "B.Fab")
		)
		(fp_line
			(start -0.120396 0.2794)
			(end 0.12065 0.2794)
			(stroke
				(width 0.1)
				(type default)
			)
			(layer "B.Fab")
		)
		(fp_line
			(start 0.67945 0.3048)
			(end 0.67945 -0.305054)
			(stroke
				(width 0.1)
				(type default)
			)
			(layer "B.Fab")
		)
		(fp_line
			(start 0.12065 0.3048)
			(end 0.67945 0.3048)
			(stroke
				(width 0.1)
				(type default)
			)
			(layer "B.Fab")
		)
		(fp_line
			(start -0.120396 0.3048)
			(end -0.120396 0.2794)
			(stroke
				(width 0.1)
				(type default)
			)
			(layer "B.Fab")
		)
		(fp_line
			(start -0.67945 0.3048)
			(end -0.120396 0.3048)
			(stroke
				(width 0.1)
				(type default)
			)
			(layer "B.Fab")
		)
		(pad "1" smd circle
			(at 0.40005 0 270)
			(size 0 0)
			(layers "B.Cu" "B.Mask" "B.Paste")
			(net "I3C_SPD_DDREFGH_CPU0_LVC1_SCL_5")
		)
		(pad "2" smd circle
			(at -0.40005 0 270)
			(size 0 0)
			(layers "B.Cu" "B.Mask" "B.Paste")
			(net "I3C_SPD_DDREFGH_CPU0_LVC1_SCL")
		)
	)
	(footprint ""
		(layer "B.Cu")
		(at 75.460098 -184.255918 -90)
		(property "Reference" "R262"
			(at 0 0 90)
			(layer "B.SilkS")
			(hide yes)
			(effects
				(font
					(size 1.27 1.27)
				)
				(justify mirror)
			)
		)
		(property "Value" ""
			(at 0 0 90)
			(layer "B.Fab")
			(effects
				(font
					(size 1.27 1.27)
				)
				(justify mirror)
			)
		)
		(duplicate_pad_numbers_are_jumpers no)
		(fp_line
			(start -0.7874 0.4064)
			(end 0.7874 0.4064)
			(stroke
				(width 0.1524)
				(type default)
			)
			(layer "B.SilkS")
		)
		(fp_line
			(start 0.7874 0.4064)
			(end 0.7874 -0.4064)
			(stroke
				(width 0.1524)
				(type default)
			)
			(layer "B.SilkS")
		)
		(fp_line
			(start -0.7874 -0.4064)
			(end -0.7874 0.4064)
			(stroke
				(width 0.1524)
				(type default)
			)
			(layer "B.SilkS")
		)
		(fp_line
			(start 0.7874 -0.4064)
			(end -0.7874 -0.4064)
			(stroke
				(width 0.1524)
				(type default)
			)
			(layer "B.SilkS")
		)
		(fp_line
			(start -0.67945 0.3048)
			(end -0.120396 0.3048)
			(stroke
				(width 0.1)
				(type default)
			)
			(layer "B.Fab")
		)
		(fp_line
			(start -0.120396 0.3048)
			(end -0.120396 0.2794)
			(stroke
				(width 0.1)
				(type default)
			)
			(layer "B.Fab")
		)
		(fp_line
			(start 0.12065 0.3048)
			(end 0.67945 0.3048)
			(stroke
				(width 0.1)
				(type default)
			)
			(layer "B.Fab")
		)
		(fp_line
			(start 0.67945 0.3048)
			(end 0.67945 -0.305054)
			(stroke
				(width 0.1)
				(type default)
			)
			(layer "B.Fab")
		)
		(fp_line
			(start -0.120396 0.2794)
			(end 0.12065 0.2794)
			(stroke
				(width 0.1)
				(type default)
			)
			(layer "B.Fab")
		)
		(fp_line
			(start 0.12065 0.2794)
			(end 0.12065 0.3048)
			(stroke
				(width 0.1)
				(type default)
			)
			(layer "B.Fab")
		)
		(fp_line
			(start -0.12065 -0.2794)
			(end -0.12065 -0.3048)
			(stroke
				(width 0.1)
				(type default)
			)
			(layer "B.Fab")
		)
		(fp_line
			(start 0.12065 -0.2794)
			(end -0.12065 -0.2794)
			(stroke
				(width 0.1)
				(type default)
			)
			(layer "B.Fab")
		)
		(fp_line
			(start -0.67945 -0.3048)
			(end -0.67945 0.3048)
			(stroke
				(width 0.1)
				(type default)
			)
			(layer "B.Fab")
		)
		(fp_line
			(start -0.12065 -0.3048)
			(end -0.67945 -0.3048)
			(stroke
				(width 0.1)
				(type default)
			)
			(layer "B.Fab")
		)
		(fp_line
			(start 0.12065 -0.305054)
			(end 0.12065 -0.2794)
			(stroke
				(width 0.1)
				(type default)
			)
			(layer "B.Fab")
		)
		(fp_line
			(start 0.67945 -0.305054)
			(end 0.12065 -0.305054)
			(stroke
				(width 0.1)
				(type default)
			)
			(layer "B.Fab")
		)
		(pad "1" smd circle
			(at 0.40005 0 90)
			(size 0 0)
			(layers "B.Cu" "B.Mask" "B.Paste")
			(net "PVNN_TERM_CPU1")
		)
		(pad "2" smd circle
			(at -0.40005 0 90)
			(size 0 0)
			(layers "B.Cu" "B.Mask" "B.Paste")
			(net "PU_CPU1_SAFE_MODE_BOOT")
		)
	)
)
